(kicad_pcb
	(version 20260206)
	(generator "pcbnew")
	(generator_version "10.0")
	(general
		(thickness 1.6)
		(legacy_teardrops no)
	)
	(paper "A4")
	(title_block
		(title "pdpb — Lightning_PDPB_BRD.brd")
		(comment 1 "Lightning (Wiwynn / Facebook NVMe JBOF) / footprints 238-244 of 1140")
	)
	(layers
		(0 "F.Cu" signal "TOP")
		(4 "In1.Cu" signal "L2GND")
		(6 "In2.Cu" signal "L3")
		(8 "In3.Cu" signal "L4VCC")
		(10 "In4.Cu" signal "L5VCC")
		(12 "In5.Cu" signal "L6")
		(14 "In6.Cu" signal "L7GND")
		(2 "B.Cu" signal "BOTTOM")
		(9 "F.Adhes" user "F.Adhesive")
		(11 "B.Adhes" user "B.Adhesive")
		(13 "F.Paste" user "Package Geometry/Pastemask Top")
		(15 "B.Paste" user "Package Geometry/Pastemask Bottom")
		(5 "F.SilkS" user "Ref Des/Silkscreen Top")
		(7 "B.SilkS" user "Ref Des/Silkscreen Bottom")
		(1 "F.Mask" user "Board Geometry/Soldermask Top")
		(3 "B.Mask" user "Board Geometry/Soldermask Bottom")
		(17 "Dwgs.User" user "User.Drawings")
		(19 "Cmts.User" user "User.Comments")
		(21 "Eco1.User" user "User.Eco1")
		(23 "Eco2.User" user "User.Eco2")
		(25 "Edge.Cuts" user "Board Geometry/Outline")
		(27 "Margin" user)
		(31 "F.CrtYd" user "Package Geometry/Place Bound Top")
		(29 "B.CrtYd" user "Package Geometry/Place Bound Bottom")
		(35 "F.Fab" user "Ref Des/Assembly Top")
		(33 "B.Fab" user "Ref Des/Assembly Bottom")
	)
	(footprint ""
		(layer "F.Cu")
		(at 51.308 -144.526 90)
		(property "Reference" "SR1138"
			(at 0 0 90)
			(layer "F.SilkS")
			(hide yes)
			(effects
				(font
					(size 1.27 1.27)
				)
			)
		)
		(property "Value" "4K7R2J-2-GP"
			(at 0.064008 -3.993896 90)
			(unlocked yes)
			(layer "F.Fab")
			(hide yes)
			(effects
				(font
					(size 1.016 1.016)
					(thickness 0.1524)
				)
			)
		)
		(property "Device Type" "R402H16"
			(at 0.064008 -5.517896 90)
			(unlocked yes)
			(layer "F.Fab")
			(hide yes)
			(effects
				(font
					(size 1.016 1.016)
					(thickness 0.1524)
				)
			)
		)
		(duplicate_pad_numbers_are_jumpers no)
		(fp_line
			(start 0.508 -0.9398)
			(end -0.508 -0.9398)
			(stroke
				(width 0.1524)
				(type default)
			)
			(layer "F.SilkS")
		)
		(fp_line
			(start -0.508 -0.9398)
			(end -0.508 0.9398)
			(stroke
				(width 0.1524)
				(type default)
			)
			(layer "F.SilkS")
		)
		(fp_rect
			(start -0.508 0.9398)
			(end 0.508 -0.9398)
			(stroke
				(width 0)
				(type default)
			)
			(fill no)
			(layer "F.CrtYd")
		)
		(fp_rect
			(start -0.508 0.9398)
			(end 0.508 -0.9398)
			(stroke
				(width 0)
				(type default)
			)
			(fill no)
			(layer "F.Fab")
		)
		(pad "1" smd custom
			(at 0 -0.4445 90)
			(size 0.1397 0.1397)
			(layers "F.Cu" "F.Mask" "F.Paste")
			(net "P3V3")
			(options
				(clearance outline)
				(anchor circle)
			)
			(primitives
				(gr_poly
					(pts
						(arc
							(start -0.1778 -0.2794)
							(mid -0.249642 -0.249642)
							(end -0.2794 -0.1778)
						)
						(arc
							(start -0.2794 0.1778)
							(mid -0.249642 0.249642)
							(end -0.1778 0.2794)
						)
						(arc
							(start 0.1778 0.2794)
							(mid 0.249642 0.249642)
							(end 0.2794 0.1778)
						)
						(arc
							(start 0.2794 -0.1778)
							(mid 0.249642 -0.249642)
							(end 0.1778 -0.2794)
						)
					)
					(width 0)
					(fill yes)
				)
			)
		)
		(pad "2" smd custom
			(at 0 0.4445 90)
			(size 0.1397 0.1397)
			(layers "F.Cu" "F.Mask" "F.Paste")
			(net "SSD_ACT_DR8")
			(options
				(clearance outline)
				(anchor circle)
			)
			(primitives
				(gr_poly
					(pts
						(arc
							(start -0.1778 -0.2794)
							(mid -0.249642 -0.249642)
							(end -0.2794 -0.1778)
						)
						(arc
							(start -0.2794 0.1778)
							(mid -0.249642 0.249642)
							(end -0.1778 0.2794)
						)
						(arc
							(start 0.1778 0.2794)
							(mid 0.249642 0.249642)
							(end 0.2794 0.1778)
						)
						(arc
							(start 0.2794 -0.1778)
							(mid 0.249642 -0.249642)
							(end 0.1778 -0.2794)
						)
					)
					(width 0)
					(fill yes)
				)
			)
		)
	)
	(footprint ""
		(layer "F.Cu")
		(at 23.998174 -268.083284 -90)
		(property "Reference" "U209"
			(at 0 0 270)
			(layer "F.SilkS")
			(hide yes)
			(effects
				(font
					(size 1.27 1.27)
				)
			)
		)
		(property "Value" "SN74LVC1G08DCKR-GP"
			(at -2.3368 -8.6868 270)
			(unlocked yes)
			(layer "F.Fab")
			(hide yes)
			(effects
				(font
					(size 1.016 1.016)
					(thickness 0.1524)
				)
			)
		)
		(property "Device Type" "SC70-5H44"
			(at -2.3114 -10.414 270)
			(unlocked yes)
			(layer "F.Fab")
			(hide yes)
			(effects
				(font
					(size 1.016 1.016)
					(thickness 0.1524)
				)
			)
		)
		(duplicate_pad_numbers_are_jumpers no)
		(fp_line
			(start -1.27 1.7018)
			(end -1.27 -1.7018)
			(stroke
				(width 0.1524)
				(type default)
			)
			(layer "F.SilkS")
		)
		(fp_line
			(start 1.27 1.7018)
			(end -1.27 1.7018)
			(stroke
				(width 0.1524)
				(type default)
			)
			(layer "F.SilkS")
		)
		(fp_line
			(start -1.27 -1.7018)
			(end 1.27 -1.7018)
			(stroke
				(width 0.1524)
				(type default)
			)
			(layer "F.SilkS")
		)
		(fp_line
			(start 1.27 -1.7018)
			(end 1.27 1.7018)
			(stroke
				(width 0.1524)
				(type default)
			)
			(layer "F.SilkS")
		)
		(fp_line
			(start 0.6604 -1.8034)
			(end 1.3843 -1.8034)
			(stroke
				(width 0.3302)
				(type default)
			)
			(layer "F.SilkS")
		)
		(fp_line
			(start 1.3843 -1.8034)
			(end 1.3843 -1.1176)
			(stroke
				(width 0.3302)
				(type default)
			)
			(layer "F.SilkS")
		)
		(fp_rect
			(start -1.524 1.9558)
			(end 1.524 -1.9558)
			(stroke
				(width 0)
				(type default)
			)
			(fill no)
			(layer "F.CrtYd")
		)
		(fp_poly
			(pts
				(xy -1.524 -1.9558) (xy 1.524 -1.9558) (xy 1.524 1.9558) (xy -1.524 1.9558)
			)
			(stroke
				(width 0)
				(type default)
			)
			(fill no)
			(layer "F.Fab")
		)
		(pad "1" smd rect
			(at 0.65024 -0.8255 270)
			(size 0.4064 1.2192)
			(layers "F.Cu" "F.Mask" "F.Paste")
			(net "SSD12_CLK0_OE_MOS_N")
		)
		(pad "2" smd rect
			(at 0 -0.8255 270)
			(size 0.4064 1.2192)
			(layers "F.Cu" "F.Mask" "F.Paste")
			(net "ATTN_LED_DR12_N")
		)
		(pad "3" smd rect
			(at -0.65024 -0.8255 270)
			(size 0.4064 1.2192)
			(layers "F.Cu" "F.Mask" "F.Paste")
			(net "GND")
		)
		(pad "4" smd rect
			(at -0.65024 0.8255 270)
			(size 0.4064 1.2192)
			(layers "F.Cu" "F.Mask" "F.Paste")
			(net "ATTN_LED_DR12_AND")
		)
		(pad "5" smd rect
			(at 0.65024 0.8255 270)
			(size 0.4064 1.2192)
			(layers "F.Cu" "F.Mask" "F.Paste")
			(net "P3V3")
		)
	)
	(footprint ""
		(layer "F.Cu")
		(at 70.739 -149.606 90)
		(property "Reference" "SR972"
			(at 0 0 90)
			(layer "F.SilkS")
			(hide yes)
			(effects
				(font
					(size 1.27 1.27)
				)
			)
		)
		(property "Value" "2KR2F-3-GP"
			(at 0.064008 -3.993896 90)
			(unlocked yes)
			(layer "F.Fab")
			(hide yes)
			(effects
				(font
					(size 1.016 1.016)
					(thickness 0.1524)
				)
			)
		)
		(property "Device Type" "R402H16"
			(at 0.064008 -5.517896 90)
			(unlocked yes)
			(layer "F.Fab")
			(hide yes)
			(effects
				(font
					(size 1.016 1.016)
					(thickness 0.1524)
				)
			)
		)
		(duplicate_pad_numbers_are_jumpers no)
		(fp_line
			(start 0.508 -0.9398)
			(end -0.508 -0.9398)
			(stroke
				(width 0.1524)
				(type default)
			)
			(layer "F.SilkS")
		)
		(fp_line
			(start -0.508 -0.9398)
			(end -0.508 0.9398)
			(stroke
				(width 0.1524)
				(type default)
			)
			(layer "F.SilkS")
		)
		(fp_rect
			(start -0.508 0.9398)
			(end 0.508 -0.9398)
			(stroke
				(width 0)
				(type default)
			)
			(fill no)
			(layer "F.CrtYd")
		)
		(fp_rect
			(start -0.508 0.9398)
			(end 0.508 -0.9398)
			(stroke
				(width 0)
				(type default)
			)
			(fill no)
			(layer "F.Fab")
		)
		(pad "1" smd custom
			(at 0 -0.4445 90)
			(size 0.1397 0.1397)
			(layers "F.Cu" "F.Mask" "F.Paste")
			(net "P3V3")
			(options
				(clearance outline)
				(anchor circle)
			)
			(primitives
				(gr_poly
					(pts
						(arc
							(start -0.1778 -0.2794)
							(mid -0.249642 -0.249642)
							(end -0.2794 -0.1778)
						)
						(arc
							(start -0.2794 0.1778)
							(mid -0.249642 0.249642)
							(end -0.1778 0.2794)
						)
						(arc
							(start 0.1778 0.2794)
							(mid 0.249642 0.249642)
							(end 0.2794 0.1778)
						)
						(arc
							(start 0.2794 -0.1778)
							(mid 0.249642 -0.249642)
							(end 0.1778 -0.2794)
						)
					)
					(width 0)
					(fill yes)
				)
			)
		)
		(pad "2" smd custom
			(at 0 0.4445 90)
			(size 0.1397 0.1397)
			(layers "F.Cu" "F.Mask" "F.Paste")
			(net "SCL_DR8")
			(options
				(clearance outline)
				(anchor circle)
			)
			(primitives
				(gr_poly
					(pts
						(arc
							(start -0.1778 -0.2794)
							(mid -0.249642 -0.249642)
							(end -0.2794 -0.1778)
						)
						(arc
							(start -0.2794 0.1778)
							(mid -0.249642 0.249642)
							(end -0.1778 0.2794)
						)
						(arc
							(start 0.1778 0.2794)
							(mid 0.249642 0.249642)
							(end 0.2794 0.1778)
						)
						(arc
							(start 0.2794 -0.1778)
							(mid 0.249642 -0.249642)
							(end 0.1778 -0.2794)
						)
					)
					(width 0)
					(fill yes)
				)
			)
		)
	)
	(footprint ""
		(layer "F.Cu")
		(at 37.1856 -211.3534 90)
		(property "Reference" "R150"
			(at 0 0 90)
			(layer "F.SilkS")
			(hide yes)
			(effects
				(font
					(size 1.27 1.27)
				)
			)
		)
		(property "Value" "4K7R2J-2-GP"
			(at 0.064008 -3.993896 90)
			(unlocked yes)
			(layer "F.Fab")
			(hide yes)
			(effects
				(font
					(size 1.016 1.016)
					(thickness 0.1524)
				)
			)
		)
		(property "Device Type" "R402H16"
			(at 0.064008 -5.517896 90)
			(unlocked yes)
			(layer "F.Fab")
			(hide yes)
			(effects
				(font
					(size 1.016 1.016)
					(thickness 0.1524)
				)
			)
		)
		(duplicate_pad_numbers_are_jumpers no)
		(fp_line
			(start 0.508 -0.9398)
			(end -0.508 -0.9398)
			(stroke
				(width 0.1524)
				(type default)
			)
			(layer "F.SilkS")
		)
		(fp_line
			(start -0.508 -0.9398)
			(end -0.508 0.9398)
			(stroke
				(width 0.1524)
				(type default)
			)
			(layer "F.SilkS")
		)
		(fp_rect
			(start -0.508 0.9398)
			(end 0.508 -0.9398)
			(stroke
				(width 0)
				(type default)
			)
			(fill no)
			(layer "F.CrtYd")
		)
		(fp_rect
			(start -0.508 0.9398)
			(end 0.508 -0.9398)
			(stroke
				(width 0)
				(type default)
			)
			(fill no)
			(layer "F.Fab")
		)
		(pad "1" smd custom
			(at 0 -0.4445 90)
			(size 0.1397 0.1397)
			(layers "F.Cu" "F.Mask" "F.Paste")
			(net "P12V")
			(options
				(clearance outline)
				(anchor circle)
			)
			(primitives
				(gr_poly
					(pts
						(arc
							(start -0.1778 -0.2794)
							(mid -0.249642 -0.249642)
							(end -0.2794 -0.1778)
						)
						(arc
							(start -0.2794 0.1778)
							(mid -0.249642 0.249642)
							(end -0.1778 0.2794)
						)
						(arc
							(start 0.1778 0.2794)
							(mid 0.249642 0.249642)
							(end 0.2794 0.1778)
						)
						(arc
							(start 0.2794 -0.1778)
							(mid 0.249642 -0.249642)
							(end 0.1778 -0.2794)
						)
					)
					(width 0)
					(fill yes)
				)
			)
		)
		(pad "2" smd custom
			(at 0 0.4445 90)
			(size 0.1397 0.1397)
			(layers "F.Cu" "F.Mask" "F.Paste")
			(net "SW_SSD12_R")
			(options
				(clearance outline)
				(anchor circle)
			)
			(primitives
				(gr_poly
					(pts
						(arc
							(start -0.1778 -0.2794)
							(mid -0.249642 -0.249642)
							(end -0.2794 -0.1778)
						)
						(arc
							(start -0.2794 0.1778)
							(mid -0.249642 0.249642)
							(end -0.1778 0.2794)
						)
						(arc
							(start 0.1778 0.2794)
							(mid 0.249642 0.249642)
							(end 0.2794 0.1778)
						)
						(arc
							(start 0.2794 -0.1778)
							(mid 0.249642 -0.249642)
							(end 0.1778 -0.2794)
						)
					)
					(width 0)
					(fill yes)
				)
			)
		)
	)
	(footprint ""
		(layer "F.Cu")
		(at 82.931 -432.8922 90)
		(property "Reference" "R9349"
			(at 0 0 90)
			(layer "F.SilkS")
			(hide yes)
			(effects
				(font
					(size 1.27 1.27)
				)
			)
		)
		(property "Value" "2D2R2F-GP"
			(at 0.064008 -3.993896 90)
			(unlocked yes)
			(layer "F.Fab")
			(hide yes)
			(effects
				(font
					(size 1.016 1.016)
					(thickness 0.1524)
				)
			)
		)
		(property "Device Type" "R402H16"
			(at 0.064008 -5.517896 90)
			(unlocked yes)
			(layer "F.Fab")
			(hide yes)
			(effects
				(font
					(size 1.016 1.016)
					(thickness 0.1524)
				)
			)
		)
		(duplicate_pad_numbers_are_jumpers no)
		(fp_line
			(start 0.508 -0.9398)
			(end -0.508 -0.9398)
			(stroke
				(width 0.1524)
				(type default)
			)
			(layer "F.SilkS")
		)
		(fp_line
			(start -0.508 -0.9398)
			(end -0.508 0.9398)
			(stroke
				(width 0.1524)
				(type default)
			)
			(layer "F.SilkS")
		)
		(fp_rect
			(start -0.508 0.9398)
			(end 0.508 -0.9398)
			(stroke
				(width 0)
				(type default)
			)
			(fill no)
			(layer "F.CrtYd")
		)
		(fp_rect
			(start -0.508 0.9398)
			(end 0.508 -0.9398)
			(stroke
				(width 0)
				(type default)
			)
			(fill no)
			(layer "F.Fab")
		)
		(pad "1" smd custom
			(at 0 -0.4445 90)
			(size 0.1397 0.1397)
			(layers "F.Cu" "F.Mask" "F.Paste")
			(net "VDD_DIFF_1")
			(options
				(clearance outline)
				(anchor circle)
			)
			(primitives
				(gr_poly
					(pts
						(arc
							(start -0.1778 -0.2794)
							(mid -0.249642 -0.249642)
							(end -0.2794 -0.1778)
						)
						(arc
							(start -0.2794 0.1778)
							(mid -0.249642 0.249642)
							(end -0.1778 0.2794)
						)
						(arc
							(start 0.1778 0.2794)
							(mid 0.249642 0.249642)
							(end 0.2794 0.1778)
						)
						(arc
							(start 0.2794 -0.1778)
							(mid 0.249642 -0.249642)
							(end 0.1778 -0.2794)
						)
					)
					(width 0)
					(fill yes)
				)
			)
		)
		(pad "2" smd custom
			(at 0 0.4445 90)
			(size 0.1397 0.1397)
			(layers "F.Cu" "F.Mask" "F.Paste")
			(net "VDDR_1")
			(options
				(clearance outline)
				(anchor circle)
			)
			(primitives
				(gr_poly
					(pts
						(arc
							(start -0.1778 -0.2794)
							(mid -0.249642 -0.249642)
							(end -0.2794 -0.1778)
						)
						(arc
							(start -0.2794 0.1778)
							(mid -0.249642 0.249642)
							(end -0.1778 0.2794)
						)
						(arc
							(start 0.1778 0.2794)
							(mid 0.249642 0.249642)
							(end 0.2794 0.1778)
						)
						(arc
							(start 0.2794 -0.1778)
							(mid 0.249642 -0.249642)
							(end 0.1778 -0.2794)
						)
					)
					(width 0)
					(fill yes)
				)
			)
		)
	)
	(footprint ""
		(layer "F.Cu")
		(at 22.86 -197.231 180)
		(property "Reference" "R9619"
			(at 0 0 180)
			(layer "F.SilkS")
			(hide yes)
			(effects
				(font
					(size 1.27 1.27)
				)
			)
		)
		(property "Value" "4K7R2J-2-GP"
			(at 0.064008 -3.993896 180)
			(unlocked yes)
			(layer "F.Fab")
			(hide yes)
			(effects
				(font
					(size 1.016 1.016)
					(thickness 0.1524)
				)
			)
		)
		(property "Device Type" "R402H16"
			(at 0.064008 -5.517896 180)
			(unlocked yes)
			(layer "F.Fab")
			(hide yes)
			(effects
				(font
					(size 1.016 1.016)
					(thickness 0.1524)
				)
			)
		)
		(duplicate_pad_numbers_are_jumpers no)
		(fp_line
			(start 0.508 -0.9398)
			(end -0.508 -0.9398)
			(stroke
				(width 0.1524)
				(type default)
			)
			(layer "F.SilkS")
		)
		(fp_line
			(start -0.508 -0.9398)
			(end -0.508 0.9398)
			(stroke
				(width 0.1524)
				(type default)
			)
			(layer "F.SilkS")
		)
		(fp_rect
			(start -0.508 0.9398)
			(end 0.508 -0.9398)
			(stroke
				(width 0)
				(type default)
			)
			(fill no)
			(layer "F.CrtYd")
		)
		(fp_rect
			(start -0.508 0.9398)
			(end 0.508 -0.9398)
			(stroke
				(width 0)
				(type default)
			)
			(fill no)
			(layer "F.Fab")
		)
		(pad "1" smd custom
			(at 0 -0.4445 180)
			(size 0.1397 0.1397)
			(layers "F.Cu" "F.Mask" "F.Paste")
			(net "P3V3")
			(options
				(clearance outline)
				(anchor circle)
			)
			(primitives
				(gr_poly
					(pts
						(arc
							(start -0.1778 -0.2794)
							(mid -0.249642 -0.249642)
							(end -0.2794 -0.1778)
						)
						(arc
							(start -0.2794 0.1778)
							(mid -0.249642 0.249642)
							(end -0.1778 0.2794)
						)
						(arc
							(start 0.1778 0.2794)
							(mid 0.249642 0.249642)
							(end 0.2794 0.1778)
						)
						(arc
							(start 0.2794 -0.1778)
							(mid 0.249642 -0.249642)
							(end 0.1778 -0.2794)
						)
					)
					(width 0)
					(fill yes)
				)
			)
		)
		(pad "2" smd custom
			(at 0 0.4445 180)
			(size 0.1397 0.1397)
			(layers "F.Cu" "F.Mask" "F.Paste")
			(net "SSD8_PWREN")
			(options
				(clearance outline)
				(anchor circle)
			)
			(primitives
				(gr_poly
					(pts
						(arc
							(start -0.1778 -0.2794)
							(mid -0.249642 -0.249642)
							(end -0.2794 -0.1778)
						)
						(arc
							(start -0.2794 0.1778)
							(mid -0.249642 0.249642)
							(end -0.1778 0.2794)
						)
						(arc
							(start 0.1778 0.2794)
							(mid 0.249642 0.249642)
							(end 0.2794 0.1778)
						)
						(arc
							(start 0.2794 -0.1778)
							(mid 0.249642 -0.249642)
							(end 0.1778 -0.2794)
						)
					)
					(width 0)
					(fill yes)
				)
			)
		)
	)
	(footprint ""
		(layer "F.Cu")
		(at 210.947 -300.9646 -90)
		(property "Reference" "Q36"
			(at 0 0 270)
			(layer "F.SilkS")
			(hide yes)
			(effects
				(font
					(size 1.27 1.27)
				)
			)
		)
		(property "Value" "2N7002A-7-GP"
			(at 0.127 -8.9662 270)
			(unlocked yes)
			(layer "F.Fab")
			(hide yes)
			(effects
				(font
					(size 1.016 1.016)
					(thickness 0.1524)
				)
			)
		)
		(property "Device Type" "SOT23DGS2D4H48"
			(at 0.127 -10.4902 270)
			(unlocked yes)
			(layer "F.Fab")
			(hide yes)
			(effects
				(font
					(size 1.016 1.016)
					(thickness 0.1524)
				)
			)
		)
		(duplicate_pad_numbers_are_jumpers no)
		(fp_line
			(start -1.651 1.778)
			(end 1.651 1.778)
			(stroke
				(width 0.1524)
				(type default)
			)
			(layer "F.SilkS")
		)
		(fp_line
			(start 1.651 1.778)
			(end 1.651 -1.778)
			(stroke
				(width 0.1524)
				(type default)
			)
			(layer "F.SilkS")
		)
		(fp_line
			(start -1.651 -1.778)
			(end -1.651 1.778)
			(stroke
				(width 0.1524)
				(type default)
			)
			(layer "F.SilkS")
		)
		(fp_line
			(start 1.651 -1.778)
			(end -1.651 -1.778)
			(stroke
				(width 0.1524)
				(type default)
			)
			(layer "F.SilkS")
		)
		(fp_poly
			(pts
				(xy -1.778 1.8796) (xy -1.778 -1.8796) (xy 1.778 -1.8796) (xy 1.778 1.8796)
			)
			(stroke
				(width 0)
				(type default)
			)
			(fill no)
			(layer "F.CrtYd")
		)
		(fp_poly
			(pts
				(xy -1.778 1.8796) (xy -1.778 -1.8796) (xy 1.778 -1.8796) (xy 1.778 1.8796)
			)
			(stroke
				(width 0)
				(type default)
			)
			(fill no)
			(layer "F.Fab")
		)
		(pad "D" smd custom
			(at 0 -0.9525 270)
			(size 0.1905 0.1905)
			(layers "F.Cu" "F.Mask" "F.Paste")
			(net "P12V_MOST2_GATE")
			(options
				(clearance outline)
				(anchor circle)
			)
			(primitives
				(gr_poly
					(pts
						(arc
							(start -0.1778 0.5715)
							(mid -0.321484 0.511984)
							(end -0.381 0.3683)
						)
						(arc
							(start -0.381 -0.3683)
							(mid -0.321484 -0.511984)
							(end -0.1778 -0.5715)
						)
						(arc
							(start 0.1778 -0.5715)
							(mid 0.321484 -0.511984)
							(end 0.381 -0.3683)
						)
						(arc
							(start 0.381 0.3683)
							(mid 0.321484 0.511984)
							(end 0.1778 0.5715)
						)
					)
					(width 0)
					(fill yes)
				)
			)
		)
		(pad "G" smd custom
			(at -0.98425 0.9525 270)
			(size 0.1905 0.1905)
			(layers "F.Cu" "F.Mask" "F.Paste")
			(net "SSD2_PWREN_R")
			(options
				(clearance outline)
				(anchor circle)
			)
			(primitives
				(gr_poly
					(pts
						(arc
							(start -0.1778 0.5715)
							(mid -0.321484 0.511984)
							(end -0.381 0.3683)
						)
						(arc
							(start -0.381 -0.3683)
							(mid -0.321484 -0.511984)
							(end -0.1778 -0.5715)
						)
						(arc
							(start 0.1778 -0.5715)
							(mid 0.321484 -0.511984)
							(end 0.381 -0.3683)
						)
						(arc
							(start 0.381 0.3683)
							(mid 0.321484 0.511984)
							(end 0.1778 0.5715)
						)
					)
					(width 0)
					(fill yes)
				)
			)
		)
		(pad "S" smd custom
			(at 0.98425 0.9525 270)
			(size 0.1905 0.1905)
			(layers "F.Cu" "F.Mask" "F.Paste")
			(net "GND")
			(options
				(clearance outline)
				(anchor circle)
			)
			(primitives
				(gr_poly
					(pts
						(arc
							(start -0.1778 0.5715)
							(mid -0.321484 0.511984)
							(end -0.381 0.3683)
						)
						(arc
							(start -0.381 -0.3683)
							(mid -0.321484 -0.511984)
							(end -0.1778 -0.5715)
						)
						(arc
							(start 0.1778 -0.5715)
							(mid 0.321484 -0.511984)
							(end 0.381 -0.3683)
						)
						(arc
							(start 0.381 0.3683)
							(mid 0.321484 0.511984)
							(end 0.1778 0.5715)
						)
					)
					(width 0)
					(fill yes)
				)
			)
		)
	)
)
